# S9S_MB_2U (Grand Teton) — schematic netlist excerpt (pin names and nets, part order shuffled) for the footprints in the layout excerpt that follows; sources: Cadence DE-HDL packaged netlist, KiCad conversion of 03242023_DA0F0TMBIJ0_F0T_Motherboard_J_brd_V01_OCP.brd

C939  Q_CAP_DIFFBUS  DIFF BUS_0.22UF 6.3V 20% X6S  pkg C0201  page 173 : \1\ = P5E_CPU0_PE2_TX_C_DP<13> ; \2\ = P5E_CPU0_PE2_TX_DP<13>
R4466  Q_RES  0 5% EMPTY  pkg 0402LF  page 196 : A = USB_HUB_2_TEST ; B = GND
PC2231  Q_CAP  1UF 25V 10% X6S  pkg C0402  page 242 : A = P12V_AUX ; B = GND

(kicad_pcb
	(version 20260206)
	(generator "pcbnew")
	(generator_version "10.0")
	(general
		(thickness 1.6)
		(legacy_teardrops no)
	)
	(paper "A4")
	(title_block
		(title "03242023_DA0F0TMBIJ0_F0T_Motherboard_J_brd_V01_OCP.brd")
		(comment 1 "Grand Teton / footprints 3528-3530 of 6105")
	)
	(layers
		(0 "F.Cu" signal "TOP")
		(4 "In1.Cu" signal "GND")
		(6 "In2.Cu" signal "IN1")
		(8 "In3.Cu" signal "GND1")
		(10 "In4.Cu" signal "IN2")
		(12 "In5.Cu" signal "GND2")
		(14 "In6.Cu" signal "IN3")
		(16 "In7.Cu" signal "GND3")
		(18 "In8.Cu" signal "VCC")
		(20 "In9.Cu" signal "VCC1")
		(22 "In10.Cu" signal "GND4")
		(24 "In11.Cu" signal "IN4")
		(26 "In12.Cu" signal "GND5")
		(28 "In13.Cu" signal "IN5")
		(30 "In14.Cu" signal "GND6")
		(32 "In15.Cu" signal "IN6")
		(34 "In16.Cu" signal "GND7")
		(2 "B.Cu" signal "BOTTOM")
		(9 "F.Adhes" user "F.Adhesive")
		(11 "B.Adhes" user "B.Adhesive")
		(13 "F.Paste" user "Package Geometry/Pastemask Top")
		(15 "B.Paste" user "Package Geometry/Pastemask Bottom")
		(5 "F.SilkS" user "Ref Des/Silkscreen Top")
		(7 "B.SilkS" user "Ref Des/Silkscreen Bottom")
		(1 "F.Mask" user "Board Geometry/Soldermask Top")
		(3 "B.Mask" user "Board Geometry/Soldermask Bottom")
		(17 "Dwgs.User" user "User.Drawings")
		(19 "Cmts.User" user "User.Comments")
		(21 "Eco1.User" user "User.Eco1")
		(23 "Eco2.User" user "User.Eco2")
		(25 "Edge.Cuts" user "Board Geometry/Outline")
		(27 "Margin" user)
		(31 "F.CrtYd" user "Package Geometry/Place Bound Top")
		(29 "B.CrtYd" user "Package Geometry/Place Bound Bottom")
		(35 "F.Fab" user "Ref Des/Assembly Top")
		(33 "B.Fab" user "Ref Des/Assembly Bottom")
	)
	(footprint ""
		(layer "F.Cu")
		(at 157.08884 -31.341568 -90)
		(property "Reference" "R4466"
			(at 0 0 270)
			(layer "F.SilkS")
			(hide yes)
			(effects
				(font
					(size 1.27 1.27)
				)
			)
		)
		(property "Value" ""
			(at 0 0 270)
			(layer "F.Fab")
			(effects
				(font
					(size 1.27 1.27)
				)
			)
		)
		(duplicate_pad_numbers_are_jumpers no)
		(fp_line
			(start -0.7874 0.4064)
			(end -0.7874 -0.4064)
			(stroke
				(width 0.1524)
				(type default)
			)
			(layer "F.SilkS")
		)
		(fp_line
			(start 0.7874 0.4064)
			(end -0.7874 0.4064)
			(stroke
				(width 0.1524)
				(type default)
			)
			(layer "F.SilkS")
		)
		(fp_line
			(start -0.7874 -0.4064)
			(end 0.7874 -0.4064)
			(stroke
				(width 0.1524)
				(type default)
			)
			(layer "F.SilkS")
		)
		(fp_line
			(start 0.7874 -0.4064)
			(end 0.7874 0.4064)
			(stroke
				(width 0.1524)
				(type default)
			)
			(layer "F.SilkS")
		)
		(fp_line
			(start -0.67945 0.3048)
			(end -0.67945 -0.305054)
			(stroke
				(width 0.1)
				(type default)
			)
			(layer "F.Fab")
		)
		(fp_line
			(start -0.12065 0.3048)
			(end -0.67945 0.3048)
			(stroke
				(width 0.1)
				(type default)
			)
			(layer "F.Fab")
		)
		(fp_line
			(start 0.120396 0.3048)
			(end 0.120396 0.2794)
			(stroke
				(width 0.1)
				(type default)
			)
			(layer "F.Fab")
		)
		(fp_line
			(start 0.67945 0.3048)
			(end 0.120396 0.3048)
			(stroke
				(width 0.1)
				(type default)
			)
			(layer "F.Fab")
		)
		(fp_line
			(start -0.12065 0.2794)
			(end -0.12065 0.3048)
			(stroke
				(width 0.1)
				(type default)
			)
			(layer "F.Fab")
		)
		(fp_line
			(start 0.120396 0.2794)
			(end -0.12065 0.2794)
			(stroke
				(width 0.1)
				(type default)
			)
			(layer "F.Fab")
		)
		(fp_line
			(start -0.12065 -0.2794)
			(end 0.12065 -0.2794)
			(stroke
				(width 0.1)
				(type default)
			)
			(layer "F.Fab")
		)
		(fp_line
			(start 0.12065 -0.2794)
			(end 0.12065 -0.3048)
			(stroke
				(width 0.1)
				(type default)
			)
			(layer "F.Fab")
		)
		(fp_line
			(start 0.12065 -0.3048)
			(end 0.67945 -0.3048)
			(stroke
				(width 0.1)
				(type default)
			)
			(layer "F.Fab")
		)
		(fp_line
			(start 0.67945 -0.3048)
			(end 0.67945 0.3048)
			(stroke
				(width 0.1)
				(type default)
			)
			(layer "F.Fab")
		)
		(fp_line
			(start -0.67945 -0.305054)
			(end -0.12065 -0.305054)
			(stroke
				(width 0.1)
				(type default)
			)
			(layer "F.Fab")
		)
		(fp_line
			(start -0.12065 -0.305054)
			(end -0.12065 -0.2794)
			(stroke
				(width 0.1)
				(type default)
			)
			(layer "F.Fab")
		)
		(pad "1" smd circle
			(at -0.40005 0 270)
			(size 0 0)
			(layers "F.Cu" "F.Mask" "F.Paste")
			(net "USB_HUB_2_TEST")
		)
		(pad "2" smd circle
			(at 0.40005 0 270)
			(size 0 0)
			(layers "F.Cu" "F.Mask" "F.Paste")
			(net "GND")
		)
	)
	(footprint ""
		(layer "F.Cu")
		(at 377.52401 -402.371052 -90)
		(property "Reference" "C939"
			(at 0 0 270)
			(layer "F.SilkS")
			(hide yes)
			(effects
				(font
					(size 1.27 1.27)
				)
			)
		)
		(property "Value" ""
			(at 0 0 270)
			(layer "F.Fab")
			(effects
				(font
					(size 1.27 1.27)
				)
			)
		)
		(duplicate_pad_numbers_are_jumpers no)
		(fp_line
			(start -0.299974 0.150114)
			(end -0.299974 -0.150114)
			(stroke
				(width 0.1)
				(type default)
			)
			(layer "F.Fab")
		)
		(fp_line
			(start 0.299974 0.150114)
			(end -0.299974 0.150114)
			(stroke
				(width 0.1)
				(type default)
			)
			(layer "F.Fab")
		)
		(fp_line
			(start -0.299974 -0.150114)
			(end 0.299974 -0.150114)
			(stroke
				(width 0.1)
				(type default)
			)
			(layer "F.Fab")
		)
		(fp_line
			(start 0.299974 -0.150114)
			(end 0.299974 0.150114)
			(stroke
				(width 0.1)
				(type default)
			)
			(layer "F.Fab")
		)
		(pad "1" smd rect
			(at -0.2667 0 270)
			(size 0.3048 0.381)
			(layers "F.Cu" "F.Mask" "F.Paste")
			(net "P5E_CPU0_PE2_TX_C_DP<13>")
		)
		(pad "2" smd rect
			(at 0.2667 0 270)
			(size 0.3048 0.381)
			(layers "F.Cu" "F.Mask" "F.Paste")
			(net "P5E_CPU0_PE2_TX_DP<13>")
		)
	)
	(footprint ""
		(layer "F.Cu")
		(at 183.878982 -34.794952 90)
		(property "Reference" "PC2231"
			(at 0 0 90)
			(layer "F.SilkS")
			(hide yes)
			(effects
				(font
					(size 1.27 1.27)
				)
			)
		)
		(property "Value" ""
			(at 0 0 90)
			(layer "F.Fab")
			(effects
				(font
					(size 1.27 1.27)
				)
			)
		)
		(duplicate_pad_numbers_are_jumpers no)
		(fp_line
			(start 0.7874 -0.4064)
			(end 0.7874 0.4064)
			(stroke
				(width 0.1524)
				(type default)
			)
			(layer "F.SilkS")
		)
		(fp_line
			(start -0.7874 -0.4064)
			(end 0.7874 -0.4064)
			(stroke
				(width 0.1524)
				(type default)
			)
			(layer "F.SilkS")
		)
		(fp_line
			(start 0.7874 0.4064)
			(end -0.7874 0.4064)
			(stroke
				(width 0.1524)
				(type default)
			)
			(layer "F.SilkS")
		)
		(fp_line
			(start -0.7874 0.4064)
			(end -0.7874 -0.4064)
			(stroke
				(width 0.1524)
				(type default)
			)
			(layer "F.SilkS")
		)
		(fp_line
			(start -0.12065 -0.305054)
			(end -0.12065 -0.2794)
			(stroke
				(width 0.1)
				(type default)
			)
			(layer "F.Fab")
		)
		(fp_line
			(start -0.67945 -0.305054)
			(end -0.12065 -0.305054)
			(stroke
				(width 0.1)
				(type default)
			)
			(layer "F.Fab")
		)
		(fp_line
			(start 0.67945 -0.3048)
			(end 0.67945 0.3048)
			(stroke
				(width 0.1)
				(type default)
			)
			(layer "F.Fab")
		)
		(fp_line
			(start 0.12065 -0.3048)
			(end 0.67945 -0.3048)
			(stroke
				(width 0.1)
				(type default)
			)
			(layer "F.Fab")
		)
		(fp_line
			(start 0.12065 -0.2794)
			(end 0.12065 -0.3048)
			(stroke
				(width 0.1)
				(type default)
			)
			(layer "F.Fab")
		)
		(fp_line
			(start -0.12065 -0.2794)
			(end 0.12065 -0.2794)
			(stroke
				(width 0.1)
				(type default)
			)
			(layer "F.Fab")
		)
		(fp_line
			(start 0.120396 0.2794)
			(end -0.12065 0.2794)
			(stroke
				(width 0.1)
				(type default)
			)
			(layer "F.Fab")
		)
		(fp_line
			(start -0.12065 0.2794)
			(end -0.12065 0.3048)
			(stroke
				(width 0.1)
				(type default)
			)
			(layer "F.Fab")
		)
		(fp_line
			(start 0.67945 0.3048)
			(end 0.120396 0.3048)
			(stroke
				(width 0.1)
				(type default)
			)
			(layer "F.Fab")
		)
		(fp_line
			(start 0.120396 0.3048)
			(end 0.120396 0.2794)
			(stroke
				(width 0.1)
				(type default)
			)
			(layer "F.Fab")
		)
		(fp_line
			(start -0.12065 0.3048)
			(end -0.67945 0.3048)
			(stroke
				(width 0.1)
				(type default)
			)
			(layer "F.Fab")
		)
		(fp_line
			(start -0.67945 0.3048)
			(end -0.67945 -0.305054)
			(stroke
				(width 0.1)
				(type default)
			)
			(layer "F.Fab")
		)
		(pad "1" smd circle
			(at -0.40005 0 90)
			(size 0 0)
			(layers "F.Cu" "F.Mask" "F.Paste")
			(net "P12V_AUX")
		)
		(pad "2" smd circle
			(at 0.40005 0 90)
			(size 0 0)
			(layers "F.Cu" "F.Mask" "F.Paste")
			(net "GND")
		)
	)
)
